(kicad_pcb
	(version 20260206)
	(generator "pcbnew")
	(generator_version "10.0")
	(general
		(thickness 1.6)
		(legacy_teardrops no)
	)
	(paper "A4")
	(title_block
		(title "dpb — 14545-sa.0730WZS0815.brd")
		(comment 1 "Honey Badger (Wiwynn) / footprints 218-221 of 1066")
	)
	(layers
		(0 "F.Cu" signal "TOP")
		(4 "In1.Cu" signal "L2GND")
		(6 "In2.Cu" signal "L3")
		(8 "In3.Cu" signal "L4VCC")
		(10 "In4.Cu" signal "L5VCC")
		(12 "In5.Cu" signal "L6")
		(14 "In6.Cu" signal "L7GND")
		(2 "B.Cu" signal "BOTTOM")
		(9 "F.Adhes" user "F.Adhesive")
		(11 "B.Adhes" user "B.Adhesive")
		(13 "F.Paste" user "Package Geometry/Pastemask Top")
		(15 "B.Paste" user "Package Geometry/Pastemask Bottom")
		(5 "F.SilkS" user "Ref Des/Silkscreen Top")
		(7 "B.SilkS" user "Ref Des/Silkscreen Bottom")
		(1 "F.Mask" user "Board Geometry/Soldermask Top")
		(3 "B.Mask" user "Board Geometry/Soldermask Bottom")
		(17 "Dwgs.User" user "User.Drawings")
		(19 "Cmts.User" user "User.Comments")
		(21 "Eco1.User" user "User.Eco1")
		(23 "Eco2.User" user "User.Eco2")
		(25 "Edge.Cuts" user "Board Geometry/Outline")
		(27 "Margin" user)
		(31 "F.CrtYd" user "Package Geometry/Place Bound Top")
		(29 "B.CrtYd" user "Package Geometry/Place Bound Bottom")
		(35 "F.Fab" user "Ref Des/Assembly Top")
		(33 "B.Fab" user "Ref Des/Assembly Bottom")
	)
	(footprint ""
		(layer "F.Cu")
		(at 215.568784 -179.929028 180)
		(property "Reference" "C155"
			(at 0 0 180)
			(layer "F.SilkS")
			(hide yes)
			(effects
				(font
					(size 1.27 1.27)
				)
			)
		)
		(property "Value" "SC10U16V6KX-2GP"
			(at -0.0762 -5.1308 180)
			(unlocked yes)
			(layer "F.Fab")
			(hide yes)
			(effects
				(font
					(size 1.016 1.016)
					(thickness 0.1524)
				)
			)
		)
		(property "Device Type" "C1206H71"
			(at -0.127 -6.6548 180)
			(unlocked yes)
			(layer "F.Fab")
			(hide yes)
			(effects
				(font
					(size 1.016 1.016)
					(thickness 0.1524)
				)
			)
		)
		(duplicate_pad_numbers_are_jumpers no)
		(fp_line
			(start 1.016 2.2352)
			(end -1.016 2.2352)
			(stroke
				(width 0.1524)
				(type default)
			)
			(layer "F.SilkS")
		)
		(fp_line
			(start 1.016 0.8382)
			(end 1.016 2.2352)
			(stroke
				(width 0.1524)
				(type default)
			)
			(layer "F.SilkS")
		)
		(fp_line
			(start 1.016 -2.2352)
			(end 1.016 -0.8382)
			(stroke
				(width 0.1524)
				(type default)
			)
			(layer "F.SilkS")
		)
		(fp_line
			(start -1.016 2.2352)
			(end -1.016 0.8382)
			(stroke
				(width 0.1524)
				(type default)
			)
			(layer "F.SilkS")
		)
		(fp_line
			(start -1.016 -0.8382)
			(end -1.016 -2.2352)
			(stroke
				(width 0.1524)
				(type default)
			)
			(layer "F.SilkS")
		)
		(fp_line
			(start -1.016 -2.2352)
			(end 1.016 -2.2352)
			(stroke
				(width 0.1524)
				(type default)
			)
			(layer "F.SilkS")
		)
		(fp_rect
			(start -1.0922 2.3114)
			(end 1.0922 -2.3114)
			(stroke
				(width 0)
				(type default)
			)
			(fill no)
			(layer "F.CrtYd")
		)
		(fp_poly
			(pts
				(xy 1.0922 -2.3114) (xy 1.0922 2.3114) (xy -1.0922 2.3114) (xy -1.0922 -2.3114)
			)
			(stroke
				(width 0)
				(type default)
			)
			(fill no)
			(layer "F.Fab")
		)
		(pad "1" smd rect
			(at 0 -1.397 180)
			(size 1.651 1.27)
			(layers "F.Cu" "F.Mask" "F.Paste")
			(net "P5V_HDD3")
		)
		(pad "2" smd rect
			(at 0 1.397 180)
			(size 1.651 1.27)
			(layers "F.Cu" "F.Mask" "F.Paste")
			(net "GND")
		)
	)
	(footprint ""
		(layer "F.Cu")
		(at 42.500042 -479.67011 90)
		(property "Reference" "SKT6"
			(at 0 0 90)
			(layer "F.SilkS")
			(hide yes)
			(effects
				(font
					(size 1.27 1.27)
				)
			)
		)
		(property "Value" "SKT-SATA14P-15P-12-GP"
			(at -22.6187 8.1788 90)
			(unlocked yes)
			(layer "F.Fab")
			(hide yes)
			(effects
				(font
					(size 1.016 1.016)
					(thickness 0.1524)
				)
			)
		)
		(property "Device Type" "87945-1001"
			(at -22.6187 6.6548 90)
			(unlocked yes)
			(layer "F.Fab")
			(hide yes)
			(effects
				(font
					(size 1.016 1.016)
					(thickness 0.1524)
				)
			)
		)
		(duplicate_pad_numbers_are_jumpers no)
		(fp_line
			(start -15.3924 -5.8547)
			(end -16.3576 -5.8547)
			(stroke
				(width 0.3302)
				(type default)
			)
			(layer "F.SilkS")
		)
		(fp_line
			(start 20.4724 -5.7658)
			(end 20.4724 -2.3114)
			(stroke
				(width 0.1524)
				(type default)
			)
			(layer "F.SilkS")
		)
		(fp_line
			(start -20.4724 -5.7658)
			(end 20.4724 -5.7658)
			(stroke
				(width 0.1524)
				(type default)
			)
			(layer "F.SilkS")
		)
		(fp_line
			(start 23.7617 -2.3114)
			(end 23.7617 2.3114)
			(stroke
				(width 0.1524)
				(type default)
			)
			(layer "F.SilkS")
		)
		(fp_line
			(start 20.4724 -2.3114)
			(end 23.7617 -2.3114)
			(stroke
				(width 0.1524)
				(type default)
			)
			(layer "F.SilkS")
		)
		(fp_line
			(start -20.4724 -2.3114)
			(end -20.4724 -5.7658)
			(stroke
				(width 0.1524)
				(type default)
			)
			(layer "F.SilkS")
		)
		(fp_line
			(start -23.7617 -2.3114)
			(end -20.4724 -2.3114)
			(stroke
				(width 0.1524)
				(type default)
			)
			(layer "F.SilkS")
		)
		(fp_line
			(start 23.117556 -0.5461)
			(end 23.117556 0.5461)
			(stroke
				(width 0.3048)
				(type default)
			)
			(layer "F.SilkS")
		)
		(fp_line
			(start -20.882356 -0.5461)
			(end -20.882356 0.5461)
			(stroke
				(width 0.3048)
				(type default)
			)
			(layer "F.SilkS")
		)
		(fp_line
			(start 20.882356 0.5461)
			(end 20.882356 -0.5461)
			(stroke
				(width 0.3048)
				(type default)
			)
			(layer "F.SilkS")
		)
		(fp_line
			(start -23.117556 0.5461)
			(end -23.117556 -0.5461)
			(stroke
				(width 0.3048)
				(type default)
			)
			(layer "F.SilkS")
		)
		(fp_line
			(start 23.7617 2.3114)
			(end 20.4724 2.3114)
			(stroke
				(width 0.1524)
				(type default)
			)
			(layer "F.SilkS")
		)
		(fp_line
			(start 20.4724 2.3114)
			(end 20.4724 9.652)
			(stroke
				(width 0.1524)
				(type default)
			)
			(layer "F.SilkS")
		)
		(fp_line
			(start -20.4724 2.3114)
			(end -23.7617 2.3114)
			(stroke
				(width 0.1524)
				(type default)
			)
			(layer "F.SilkS")
		)
		(fp_line
			(start -23.7617 2.3114)
			(end -23.7617 -2.3114)
			(stroke
				(width 0.1524)
				(type default)
			)
			(layer "F.SilkS")
		)
		(fp_line
			(start 17.8435 7.9502)
			(end -17.8435 7.9502)
			(stroke
				(width 0.1524)
				(type default)
			)
			(layer "F.SilkS")
		)
		(fp_line
			(start -17.8435 7.9502)
			(end -17.8435 9.652)
			(stroke
				(width 0.1524)
				(type default)
			)
			(layer "F.SilkS")
		)
		(fp_line
			(start 20.4724 9.652)
			(end 17.8435 9.652)
			(stroke
				(width 0.1524)
				(type default)
			)
			(layer "F.SilkS")
		)
		(fp_line
			(start 17.8435 9.652)
			(end 17.8435 7.9502)
			(stroke
				(width 0.1524)
				(type default)
			)
			(layer "F.SilkS")
		)
		(fp_line
			(start -17.8435 9.652)
			(end -20.4724 9.652)
			(stroke
				(width 0.1524)
				(type default)
			)
			(layer "F.SilkS")
		)
		(fp_line
			(start -20.4724 9.652)
			(end -20.4724 2.3114)
			(stroke
				(width 0.1524)
				(type default)
			)
			(layer "F.SilkS")
		)
		(fp_arc
			(start 20.882356 -0.5461)
			(mid 21.999956 -1.6637)
			(end 23.117556 -0.5461)
			(stroke
				(width 0.3048)
				(type default)
			)
			(layer "F.SilkS")
		)
		(fp_arc
			(start -23.117556 -0.5461)
			(mid -21.999956 -1.6637)
			(end -20.882356 -0.5461)
			(stroke
				(width 0.3048)
				(type default)
			)
			(layer "F.SilkS")
		)
		(fp_arc
			(start 23.117556 0.5461)
			(mid 21.999956 1.6637)
			(end 20.882356 0.5461)
			(stroke
				(width 0.3048)
				(type default)
			)
			(layer "F.SilkS")
		)
		(fp_arc
			(start -20.882356 0.5461)
			(mid -21.999956 1.6637)
			(end -23.117556 0.5461)
			(stroke
				(width 0.3048)
				(type default)
			)
			(layer "F.SilkS")
		)
		(fp_poly
			(pts
				(xy -15.87119 -5.838698) (xy -15.23619 -6.473698) (xy -16.50619 -6.473698)
			)
			(stroke
				(width 0)
				(type default)
			)
			(fill yes)
			(layer "F.SilkS")
		)
		(fp_poly
			(pts
				(xy -20.2184 -5.5118) (xy 20.2184 -5.5118) (xy 20.2184 -2.0574) (xy 23.5077 -2.0574) (xy 23.5077 2.0574)
				(xy 20.2184 2.0574) (xy 20.2184 9.398) (xy 18.0975 9.398) (xy 18.0975 7.6962) (xy -18.0975 7.6962)
				(xy -18.0975 9.398) (xy -20.2184 9.398) (xy -20.2184 2.0574) (xy -23.5077 2.0574) (xy -23.5077 -2.0574)
				(xy -20.2184 -2.0574)
			)
			(stroke
				(width 0)
				(type default)
			)
			(fill no)
			(layer "F.CrtYd")
		)
		(fp_poly
			(pts
				(xy -20.2184 -5.5118) (xy -20.2184 -6.0198) (xy -20.7264 -6.0198) (xy -20.7264 -2.5654) (xy -24.0157 -2.5654)
				(xy -24.0157 2.5654) (xy -20.7264 2.5654) (xy -20.7264 9.906) (xy -17.5895 9.906) (xy -17.5895 8.2042)
				(xy 17.5895 8.2042) (xy 17.5895 9.906) (xy 20.7264 9.906) (xy 20.7264 2.5654) (xy 24.0157 2.5654)
				(xy 24.0157 -2.5654) (xy 20.7264 -2.5654) (xy 20.7264 -6.0198) (xy -20.21586 -6.0198) (xy -20.21586 -5.5118)
				(xy 20.2184 -5.5118) (xy 20.2184 -2.0574) (xy 23.5077 -2.0574) (xy 23.5077 2.0574) (xy 20.2184 2.0574)
				(xy 20.2184 9.398) (xy 18.0975 9.398) (xy 18.0975 7.6962) (xy -18.0975 7.6962) (xy -18.0975 9.398)
				(xy -20.2184 9.398) (xy -20.2184 2.0574) (xy -23.5077 2.0574) (xy -23.5077 -2.0574) (xy -20.2184 -2.0574)
			)
			(stroke
				(width 0)
				(type default)
			)
			(fill no)
			(layer "F.CrtYd")
		)
		(fp_poly
			(pts
				(xy -20.7264 -6.0198) (xy -20.7264 -2.5654) (xy -24.0157 -2.5654) (xy -24.0157 2.5654) (xy -20.7264 2.5654)
				(xy -20.7264 9.906) (xy -17.5895 9.906) (xy -17.5895 8.2042) (xy 17.5895 8.2042) (xy 17.5895 9.906)
				(xy 20.7264 9.906) (xy 20.7264 2.5654) (xy 24.0157 2.5654) (xy 24.0157 -2.5654) (xy 20.7264 -2.5654)
				(xy 20.7264 -6.0198)
			)
			(stroke
				(width 0)
				(type default)
			)
			(fill no)
			(layer "F.Fab")
		)
		(pad "" np_thru_hole circle
			(at -18.999962 -2.350008 90)
			(size 0.254 0.254)
			(drill 1.8542)
			(layers "*.Cu" "*.Mask")
			(clearance 1.1557)
			(thermal_gap 1.1557)
		)
		(pad "" np_thru_hole circle
			(at 18.999962 -2.350008 90)
			(size 0.254 0.254)
			(drill 1.8542)
			(layers "*.Cu" "*.Mask")
			(clearance 1.1557)
			(thermal_gap 1.1557)
		)
		(pad "H1" thru_hole oval
			(at -21.999956 0 90)
			(size 1.524 2.6162)
			(drill oval 0.8128 1.905)
			(layers "*.Cu" "*.Mask")
			(remove_unused_layers no)
			(net "GND")
			(clearance 0.1524)
			(thermal_gap 0.1524)
		)
		(pad "H2" thru_hole oval
			(at 21.999956 0 90)
			(size 1.524 2.6162)
			(drill oval 0.8128 1.905)
			(layers "*.Cu" "*.Mask")
			(remove_unused_layers no)
			(net "GND")
			(clearance 0.1524)
			(thermal_gap 0.1524)
		)
		(pad "P1" smd rect
			(at -1.89992 -4.249928 90)
			(size 0.6604 2.3876)
			(layers "F.Cu" "F.Mask" "F.Paste")
			(net "Net_20")
		)
		(pad "P2" smd rect
			(at -0.62992 -4.249928 90)
			(size 0.6604 2.3876)
			(layers "F.Cu" "F.Mask" "F.Paste")
			(net "Net_19")
		)
		(pad "P3" smd rect
			(at 0.64008 -4.249928 90)
			(size 0.6604 2.3876)
			(layers "F.Cu" "F.Mask" "F.Paste")
			(net "Net_18")
		)
		(pad "P4" smd rect
			(at 1.91008 -4.249928 90)
			(size 0.6604 2.3876)
			(layers "F.Cu" "F.Mask" "F.Paste")
			(net "GND")
		)
		(pad "P5" smd rect
			(at 3.18008 -4.249928 90)
			(size 0.6604 2.3876)
			(layers "F.Cu" "F.Mask" "F.Paste")
			(net "HDD_PRSNT_NET5")
		)
		(pad "P6" smd rect
			(at 4.45008 -4.249928 90)
			(size 0.6604 2.3876)
			(layers "F.Cu" "F.Mask" "F.Paste")
			(net "GND")
		)
		(pad "P7" smd rect
			(at 5.72008 -4.249928 90)
			(size 0.6604 2.3876)
			(layers "F.Cu" "F.Mask" "F.Paste")
			(net "5V_PRE_5")
		)
		(pad "P8" smd rect
			(at 6.99008 -4.249928 90)
			(size 0.6604 2.3876)
			(layers "F.Cu" "F.Mask" "F.Paste")
			(net "P5V_HDD5")
		)
		(pad "P9" smd rect
			(at 8.26008 -4.249928 90)
			(size 0.6604 2.3876)
			(layers "F.Cu" "F.Mask" "F.Paste")
			(net "P5V_HDD5")
		)
		(pad "P10" smd rect
			(at 9.53008 -4.249928 90)
			(size 0.6604 2.3876)
			(layers "F.Cu" "F.Mask" "F.Paste")
			(net "GND")
		)
		(pad "P11" smd rect
			(at 10.80008 -4.249928 90)
			(size 0.6604 2.3876)
			(layers "F.Cu" "F.Mask" "F.Paste")
			(net "ACT_HDD5")
		)
		(pad "P12" smd rect
			(at 12.07008 -4.249928 90)
			(size 0.6604 2.3876)
			(layers "F.Cu" "F.Mask" "F.Paste")
			(net "GND")
		)
		(pad "P13" smd rect
			(at 13.34008 -4.249928 90)
			(size 0.6604 2.3876)
			(layers "F.Cu" "F.Mask" "F.Paste")
			(net "12V_PRE_5")
		)
		(pad "P14" smd rect
			(at 14.61008 -4.249928 90)
			(size 0.6604 2.3876)
			(layers "F.Cu" "F.Mask" "F.Paste")
			(net "P12V_HDD5")
		)
		(pad "P15" smd rect
			(at 15.88008 -4.249928 90)
			(size 0.6604 2.3876)
			(layers "F.Cu" "F.Mask" "F.Paste")
			(net "P12V_HDD5")
		)
		(pad "S1" smd rect
			(at -15.86992 -4.249928 90)
			(size 0.6604 2.3876)
			(layers "F.Cu" "F.Mask" "F.Paste")
			(net "GND")
		)
		(pad "S2" smd rect
			(at -14.59992 -4.249928 90)
			(size 0.6604 2.3876)
			(layers "F.Cu" "F.Mask" "F.Paste")
			(net "SAS2X28_A_HDD5_TX_+")
		)
		(pad "S3" smd rect
			(at -13.32992 -4.249928 90)
			(size 0.6604 2.3876)
			(layers "F.Cu" "F.Mask" "F.Paste")
			(net "SAS2X28_A_HDD5_TX_-")
		)
		(pad "S4" smd rect
			(at -12.05992 -4.249928 90)
			(size 0.6604 2.3876)
			(layers "F.Cu" "F.Mask" "F.Paste")
			(net "GND")
		)
		(pad "S5" smd rect
			(at -10.78992 -4.249928 90)
			(size 0.6604 2.3876)
			(layers "F.Cu" "F.Mask" "F.Paste")
			(net "SAS2X28_DRIVE_RX_N_A5")
		)
		(pad "S6" smd rect
			(at -9.51992 -4.249928 90)
			(size 0.6604 2.3876)
			(layers "F.Cu" "F.Mask" "F.Paste")
			(net "SAS2X28_DRIVE_RX_P_A5")
		)
		(pad "S7" smd rect
			(at -8.24992 -4.249928 90)
			(size 0.6604 2.3876)
			(layers "F.Cu" "F.Mask" "F.Paste")
			(net "GND")
		)
		(pad "S8" smd rect
			(at -7.480046 -2.100072 90)
			(size 0.508 1.905)
			(layers "F.Cu" "F.Mask" "F.Paste")
			(net "GND")
		)
		(pad "S9" smd rect
			(at -6.679946 -2.100072 90)
			(size 0.508 1.905)
			(layers "F.Cu" "F.Mask" "F.Paste")
			(net "SAS2X28_B_HDD5_TX_+")
		)
		(pad "S10" smd rect
			(at -5.8801 -2.100072 90)
			(size 0.508 1.905)
			(layers "F.Cu" "F.Mask" "F.Paste")
			(net "SAS2X28_B_HDD5_TX_-")
		)
		(pad "S11" smd rect
			(at -5.08 -2.100072 90)
			(size 0.508 1.905)
			(layers "F.Cu" "F.Mask" "F.Paste")
			(net "GND")
		)
		(pad "S12" smd rect
			(at -4.2799 -2.100072 90)
			(size 0.508 1.905)
			(layers "F.Cu" "F.Mask" "F.Paste")
			(net "SAS2X28_DRIVE_RX_N_B5")
		)
		(pad "S13" smd rect
			(at -3.480054 -2.100072 90)
			(size 0.508 1.905)
			(layers "F.Cu" "F.Mask" "F.Paste")
			(net "SAS2X28_DRIVE_RX_P_B5")
		)
		(pad "S14" smd rect
			(at -2.679954 -2.100072 90)
			(size 0.508 1.905)
			(layers "F.Cu" "F.Mask" "F.Paste")
			(net "GND")
		)
		(zone
			(layers "F.Cu" "B.Cu" "In1.Cu" "In2.Cu" "In3.Cu" "In4.Cu" "In5.Cu" "In6.Cu")
			(hatch none 0.5)
			(connect_pads
				(clearance 0)
			)
			(min_thickness 0.25)
			(keepout
				(tracks not_allowed)
				(vias allowed)
				(pads allowed)
				(copperpour not_allowed)
				(footprints allowed)
			)
			(placement
				(enabled no)
				(sheetname "")
			)
			(fill
				(thermal_gap 0.5)
				(thermal_bridge_width 0.5)
				(island_removal_mode 0)
			)
			(polygon
				(pts
					(arc
						(start 41.381934 -498.670072)
						(mid 38.918134 -498.670072)
						(end 41.381934 -498.670072)
					)
				)
			)
		)
		(zone
			(layers "F.Cu" "B.Cu" "In1.Cu" "In2.Cu" "In3.Cu" "In4.Cu" "In5.Cu" "In6.Cu")
			(hatch none 0.5)
			(connect_pads
				(clearance 0)
			)
			(min_thickness 0.25)
			(keepout
				(tracks not_allowed)
				(vias allowed)
				(pads allowed)
				(copperpour not_allowed)
				(footprints allowed)
			)
			(placement
				(enabled no)
				(sheetname "")
			)
			(fill
				(thermal_gap 0.5)
				(thermal_bridge_width 0.5)
				(island_removal_mode 0)
			)
			(polygon
				(pts
					(arc
						(start 41.381934 -460.670148)
						(mid 38.918134 -460.670148)
						(end 41.381934 -460.670148)
					)
				)
			)
		)
	)
	(footprint ""
		(layer "F.Cu")
		(at 242.569746 -16.2687 90)
		(property "Reference" "PC4"
			(at 0 0 90)
			(layer "F.SilkS")
			(hide yes)
			(effects
				(font
					(size 1.27 1.27)
				)
			)
		)
		(property "Value" "SC22U25V5MX-GP"
			(at -0.0762 -6.1214 90)
			(unlocked yes)
			(layer "F.Fab")
			(hide yes)
			(effects
				(font
					(size 1.016 1.016)
					(thickness 0.1524)
				)
			)
		)
		(property "Device Type" "C805H58"
			(at -0.0762 -8.1534 90)
			(unlocked yes)
			(layer "F.Fab")
			(hide yes)
			(effects
				(font
					(size 1.016 1.016)
					(thickness 0.1524)
				)
			)
		)
		(duplicate_pad_numbers_are_jumpers no)
		(fp_line
			(start 0.635 0)
			(end -0.635 0)
			(stroke
				(width 0.508)
				(type default)
			)
			(layer "F.SilkS")
		)
		(fp_rect
			(start -0.9652 1.778)
			(end 0.9652 -1.778)
			(stroke
				(width 0)
				(type default)
			)
			(fill no)
			(layer "F.CrtYd")
		)
		(fp_poly
			(pts
				(xy -0.9652 -1.778) (xy 0.9652 -1.778) (xy 0.9652 1.778) (xy -0.9652 1.778)
			)
			(stroke
				(width 0)
				(type default)
			)
			(fill no)
			(layer "F.Fab")
		)
		(pad "1" smd rect
			(at 0 -0.9652 90)
			(size 1.397 1.143)
			(layers "F.Cu" "F.Mask" "F.Paste")
			(net "P5VA_12VIN")
		)
		(pad "2" smd rect
			(at 0 0.9652 90)
			(size 1.397 1.143)
			(layers "F.Cu" "F.Mask" "F.Paste")
			(net "GND")
		)
	)
	(footprint ""
		(layer "F.Cu")
		(at 98.933 -18.796 180)
		(property "Reference" "C339"
			(at 0 0 180)
			(layer "F.SilkS")
			(hide yes)
			(effects
				(font
					(size 1.27 1.27)
				)
			)
		)
		(property "Value" "SCD1U10V2KX-5GP"
			(at 1.1811 -2.7051 180)
			(unlocked yes)
			(layer "F.Fab")
			(hide yes)
			(effects
				(font
					(size 1.016 1.016)
					(thickness 0.1524)
				)
			)
		)
		(property "Device Type" "C402H22"
			(at 1.1811 -4.2291 180)
			(unlocked yes)
			(layer "F.Fab")
			(hide yes)
			(effects
				(font
					(size 1.016 1.016)
					(thickness 0.1524)
				)
			)
		)
		(duplicate_pad_numbers_are_jumpers no)
		(fp_rect
			(start -0.4318 0.9525)
			(end 0.4318 -0.9525)
			(stroke
				(width 0)
				(type default)
			)
			(fill no)
			(layer "F.CrtYd")
		)
		(fp_rect
			(start -0.4318 0.9525)
			(end 0.4318 -0.9525)
			(stroke
				(width 0)
				(type default)
			)
			(fill no)
			(layer "F.Fab")
		)
		(pad "1" smd custom
			(at 0 -0.4445 180)
			(size 0.1524 0.1524)
			(layers "F.Cu" "F.Mask" "F.Paste")
			(net "P3V3")
			(options
				(clearance outline)
				(anchor circle)
			)
			(primitives
				(gr_poly
					(pts
						(arc
							(start 0.3048 -0.2032)
							(mid 0.275042 -0.275042)
							(end 0.2032 -0.3048)
						)
						(arc
							(start -0.2032 -0.3048)
							(mid -0.275042 -0.275042)
							(end -0.3048 -0.2032)
						)
						(arc
							(start -0.3048 0.2032)
							(mid -0.275042 0.275042)
							(end -0.2032 0.3048)
						)
						(arc
							(start 0.2032 0.3048)
							(mid 0.275042 0.275042)
							(end 0.3048 0.2032)
						)
					)
					(width 0)
					(fill yes)
				)
			)
		)
		(pad "2" smd custom
			(at 0 0.4445 180)
			(size 0.1524 0.1524)
			(layers "F.Cu" "F.Mask" "F.Paste")
			(net "GND")
			(options
				(clearance outline)
				(anchor circle)
			)
			(primitives
				(gr_poly
					(pts
						(arc
							(start 0.3048 -0.2032)
							(mid 0.275042 -0.275042)
							(end 0.2032 -0.3048)
						)
						(arc
							(start -0.2032 -0.3048)
							(mid -0.275042 -0.275042)
							(end -0.3048 -0.2032)
						)
						(arc
							(start -0.3048 0.2032)
							(mid -0.275042 0.275042)
							(end -0.2032 0.3048)
						)
						(arc
							(start 0.2032 0.3048)
							(mid 0.275042 0.275042)
							(end 0.3048 0.2032)
						)
					)
					(width 0)
					(fill yes)
				)
			)
		)
	)
)
